FILE_TYPE = CONNECTIVITY;
{Allegro Design Entry HDL 16.6-p007 (v16-6-112F) 10/10/2012}
"PAGE_NUMBER" = 49;
0"NC";
1"M_D_DQS_DP<17:0>";
2"M_D_DQS_DN<17:0>";
3"M_D_BG<1:0>";
4"M_D_MA<17:0>";
5"M_D_BA<1:0>";
6"M_D_DQ<63:0>";
7"M_D_CLK_DP<3:0>";
8"M_D_CKE<3:0>";
9"M_D_CS_N<7:0>";
10"M_D_ECC<7:0>";
11"M_D_CLK_DN<3:0>";
12"M_D_ODT<3:0>";
13"PVDDQ_DEF\g";
14"PVTT_DEF\g";
15"GND\g";
16"GND\g"ROOM"TBD"BOM_COST"TBD";
17"GND\g";
18"PVPP_DEF\g";
19"PVPP_DEF\g";
20"P12V_NVDIMM_DEF\g";
21"GND\g";
22"M_D_VREF";
23"TP_CH_D_DIMM_D0_RFU_1";
24"TP_CH_D_DIMM_D0_RFU_0";
25"TP_CH_D_DIMM_D0_RFU_2";
26"FM_ADR_COMPLETE_DEF_N";
27"FM_DIMM_EVENT_COD_N";
28"M_DEF_RST_N";
29"M_D_PAR";
30"M_D_C<2>";
31"M_D_CS_N<0>";
32"M_D_ODT<1>";
33"M_D_ODT<0>";
34"M_D_ECC<6>";
35"M_D_CKE<1>";
36"M_D_CLK_DN<0>";
37"M_D_ECC<1>";
38"M_D_ECC<0>";
39"M_D_ECC<3>";
40"M_D_ECC<2>";
41"M_D_ECC<5>";
42"M_D_ECC<4>";
43"M_D_ECC<7>";
44"M_D_CS_N<1>";
45"M_D_CS_N<2>";
46"M_D_CS_N<3>";
47"M_D_CKE<0>";
48"M_D_BG<0>";
49"M_D_CLK_DP<1>";
50"M_D_CLK_DN<1>";
51"M_D_CLK_DP<0>";
52"M_D_ACT_N";
53"M_D_ALERT_N";
54"SMB_DDR_DEF_VPP_SDA";
55"SMB_DDR_DEF_VPP_SCL";
56"M_D_DQ<1>";
57"M_D_DQ<4>";
58"M_D_DQ<5>";
59"M_D_DQ<2>";
60"M_D_DQ<3>";
61"M_D_DQ<0>";
62"M_D_DQ<7>";
63"M_D_DQ<9>";
64"M_D_DQ<8>";
65"M_D_DQ<11>";
66"M_D_DQ<10>";
67"M_D_DQ<6>";
68"M_D_DQ<14>";
69"M_D_DQ<13>";
70"M_D_DQ<12>";
71"M_D_DQ<15>";
72"M_D_DQ<17>";
73"M_D_DQ<16>";
74"M_D_DQ<19>";
75"M_D_DQ<18>";
76"M_D_DQ<21>";
77"M_D_DQ<20>";
78"M_D_DQ<27>";
79"M_D_DQ<23>";
80"M_D_DQ<22>";
81"M_D_DQ<25>";
82"M_D_DQ<24>";
83"M_D_DQ<26>";
84"M_D_DQ<31>";
85"M_D_DQ<30>";
86"M_D_DQ<29>";
87"M_D_DQ<28>";
88"M_D_DQ<37>";
89"M_D_DQ<34>";
90"M_D_DQ<33>";
91"M_D_DQ<32>";
92"M_D_DQ<35>";
93"M_D_DQ<39>";
94"M_D_DQ<36>";
95"M_D_DQ<38>";
96"M_D_DQ<41>";
97"M_D_DQ<40>";
98"M_D_MA<16>";
99"M_D_MA<15>";
100"M_D_MA<14>";
101"M_D_MA<11>";
102"M_D_MA<10>";
103"M_D_MA<2>";
104"M_D_BA<0>";
105"M_D_MA<9>";
106"M_D_MA<8>";
107"M_D_MA<7>";
108"M_D_MA<6>";
109"M_D_MA<5>";
110"M_D_MA<3>";
111"M_D_MA<17>";
112"M_D_MA<13>";
113"M_D_MA<12>";
114"M_D_MA<1>";
115"M_D_MA<0>";
116"M_D_BA<1>";
117"M_D_MA<4>";
118"M_D_BG<1>";
119"M_D_DQ<46>";
120"M_D_DQ<43>";
121"M_D_DQ<42>";
122"M_D_DQ<45>";
123"M_D_DQ<44>";
124"M_D_DQ<47>";
125"M_D_DQ<49>";
126"M_D_DQ<48>";
127"M_D_DQ<51>";
128"M_D_DQ<50>";
129"M_D_DQ<53>";
130"M_D_DQ<52>";
131"M_D_DQ<55>";
132"M_D_DQ<56>";
133"M_D_DQ<54>";
134"M_D_DQ<57>";
135"M_D_DQ<63>";
136"M_D_DQ<60>";
137"M_D_DQ<59>";
138"M_D_DQ<58>";
139"M_D_DQ<61>";
140"M_D_DQ<62>";
141"M_D_DQS_DN<6>";
142"M_D_DQS_DP<5>";
143"M_D_DQS_DN<5>";
144"M_D_DQS_DP<4>";
145"M_D_DQS_DN<4>";
146"M_D_DQS_DP<3>";
147"M_D_DQS_DN<3>";
148"M_D_DQS_DP<2>";
149"M_D_DQS_DN<2>";
150"M_D_DQS_DP<1>";
151"M_D_DQS_DN<1>";
152"M_D_DQS_DP<0>";
153"M_D_DQS_DN<0>";
154"M_D_DQS_DP<9>";
155"M_D_DQS_DN<9>";
156"M_D_DQS_DP<8>";
157"M_D_DQS_DN<8>";
158"M_D_DQS_DP<7>";
159"M_D_DQS_DN<7>";
160"M_D_DQS_DP<6>";
161"M_D_DQS_DP<16>";
162"M_D_DQS_DN<16>";
163"M_D_DQS_DP<15>";
164"M_D_DQS_DN<15>";
165"M_D_DQS_DP<14>";
166"M_D_DQS_DN<14>";
167"M_D_DQS_DP<13>";
168"M_D_DQS_DN<13>";
169"M_D_DQS_DP<12>";
170"M_D_DQS_DN<12>";
171"M_D_DQS_DP<11>";
172"M_D_DQS_DN<11>";
173"M_D_DQS_DP<10>";
174"M_D_DQS_DN<10>";
175"M_D_DQS_DP<17>";
176"M_D_DQS_DN<17>";
%"TAP"
"6","(650,5100)","2","mstr_standard","I10";
;
HDL_TAP"TRUE"
BODY_TYPE"PLUMBING"
CDS_LIB"mstr_standard";
"B \NAC \NWC"1;
"S \NAC"
BN"16"161;
%"TAP"
"6","(-1750,2500)","2","mstr_standard","I100";
;
HDL_TAP"TRUE"
BODY_TYPE"PLUMBING"
CDS_LIB"mstr_standard";
"B \NAC \NWC"6;
"S \NAC"
BN"11"65;
%"TAP"
"6","(-1750,2450)","2","mstr_standard","I101";
;
HDL_TAP"TRUE"
BODY_TYPE"PLUMBING"
CDS_LIB"mstr_standard";
"B \NAC \NWC"6;
"S \NAC"
BN"8"64;
%"TAP"
"6","(-1750,2350)","2","mstr_standard","I102";
;
HDL_TAP"TRUE"
BODY_TYPE"PLUMBING"
CDS_LIB"mstr_standard";
"B \NAC \NWC"6;
"S \NAC"
BN"6"67;
%"TAP"
"6","(-1750,2400)","2","mstr_standard","I103";
;
HDL_TAP"TRUE"
BODY_TYPE"PLUMBING"
CDS_LIB"mstr_standard";
"B \NAC \NWC"6;
"S \NAC"
BN"9"63;
%"TAP"
"6","(-1750,2300)","2","mstr_standard","I104";
;
HDL_TAP"TRUE"
BODY_TYPE"PLUMBING"
CDS_LIB"mstr_standard";
"B \NAC \NWC"6;
"S \NAC"
BN"7"62;
%"TAP"
"6","(-1750,2250)","2","mstr_standard","I105";
;
HDL_TAP"TRUE"
BODY_TYPE"PLUMBING"
CDS_LIB"mstr_standard";
"B \NAC \NWC"6;
"S \NAC"
BN"4"57;
%"TAP"
"6","(-1750,2150)","2","mstr_standard","I106";
;
HDL_TAP"TRUE"
BODY_TYPE"PLUMBING"
CDS_LIB"mstr_standard";
"B \NAC \NWC"6;
"S \NAC"
BN"2"59;
%"TAP"
"6","(-1750,2200)","2","mstr_standard","I107";
;
HDL_TAP"TRUE"
BODY_TYPE"PLUMBING"
CDS_LIB"mstr_standard";
"B \NAC \NWC"6;
"S \NAC"
BN"5"58;
%"TAP"
"6","(-1750,2050)","2","mstr_standard","I108";
;
HDL_TAP"TRUE"
BODY_TYPE"PLUMBING"
CDS_LIB"mstr_standard";
"B \NAC \NWC"6;
"S \NAC"
BN"0"61;
%"TAP"
"6","(-1750,2100)","2","mstr_standard","I109";
;
HDL_TAP"TRUE"
BODY_TYPE"PLUMBING"
CDS_LIB"mstr_standard";
"B \NAC \NWC"6;
"S \NAC"
BN"3"60;
%"TAP"
"6","(650,5000)","2","mstr_standard","I11";
;
HDL_TAP"TRUE"
BODY_TYPE"PLUMBING"
CDS_LIB"mstr_standard";
"B \NAC \NWC"1;
"S \NAC"
BN"15"163;
%"TAP"
"6","(-1750,2000)","2","mstr_standard","I110";
;
HDL_TAP"TRUE"
BODY_TYPE"PLUMBING"
CDS_LIB"mstr_standard";
"B \NAC \NWC"6;
"S \NAC"
BN"1"56;
%"SCONN288_H44441004"
"1","(-2500,3500)","0","mstr_sconn","I111";
;
CDS_SEC"1"
ROOM"DDR4_CH_D"
CDS_LOCATION"J4B1"
SEC"1"
SEC_TYPE"PIP"
CDS_LIB"mstr_sconn"
BOM_COST"MEM"
PACK_TYPE"PIP"
MATERIAL"SCONN"
PART_NUMBER"H44441-004"
LOCATION"J4B1";
"DQ<63>"
$PN"280"140;
"DQ<62>"
$PN"135"135;
"DQ<61>"
$PN"273"136;
"DQ<5>"
$PN"148"57;
"DQ<4>"
$PN"3"58;
"DQ<3>"
$PN"157"59;
"DQ<2>"
$PN"12"60;
"DQ<47>"
$PN"258"119;
"DQ<48>"
$PN"119"125;
"DQ<49>"
$PN"264"126;
"DQ<50>"
$PN"126"127;
"DQ<51>"
$PN"271"128;
"DQ<52>"
$PN"117"129;
"DQ<53>"
$PN"262"130;
"DQ<54>"
$PN"124"131;
"DQ<58>"
$PN"137"137;
"DQ<57>"
$PN"275"132;
"SAVE_N_NC"
$PN"230"26;
"RFU<1>"
$PN"227"23;
"RFU<0>"
$PN"205"24;
"DQ<17>"
$PN"172"73;
"DQ<15>"
$PN"166"68;
"DQ<26>"
$PN"45"78;
"DQ<27>"
$PN"190"83;
"S0_N"
$PN"84"31;
"CKE<0>"
$PN"60"47;
"ODT<1>"
$PN"91"32;
"ODT<0>"
$PN"87"33;
"CB<7>"
$PN"199"34;
"A16_RAS_N"
$PN"82"98;
"A15_CAS_N"
$PN"86"99;
"A14_WE_N"
$PN"228"100;
"A11"
$PN"210"101;
"A10"
$PN"225"102;
"DQ<38>"
$PN"102"93;
"DQ<36>"
$PN"95"88;
"DQ<35>"
$PN"249"89;
"A2"
$PN"216"103;
"ALERT_N"
$PN"208"53;
"ACT_N"
$PN"62"52;
"DQ<0>"
$PN"5"56;
"DQ<1>"
$PN"150"61;
"SA<1>"
$PN"140"16;
"SA<2>"
$PN"238"16;
"VDDSPD"
$PN"284"19;
"SA<0>"
$PN"139"16;
"BA<0>"
$PN"81"104;
"BG<1>"
$PN"207"118;
"BG<0>"
$PN"63"48;
"CK1P"
$PN"218"49;
"VREFCA"
$PN"146"22;
"SDA"
$PN"285"54;
"SCL"
$PN"141"55;
"RFU<2>"
$PN"144"25;
"RESET_N"
$PN"58"28;
"PAR"
$PN"222"29;
"EVENT_N"
$PN"78"27;
"DQ<6>"
$PN"10"62;
"DQ<7>"
$PN"155"67;
"DQ<8>"
$PN"16"63;
"DQ<9>"
$PN"161"64;
"DQ<10>"
$PN"23"65;
"DQ<11>"
$PN"168"66;
"DQ<12>"
$PN"14"69;
"DQ<13>"
$PN"159"70;
"DQ<14>"
$PN"21"71;
"DQ<16>"
$PN"27"72;
"DQ<18>"
$PN"34"74;
"DQ<19>"
$PN"179"75;
"DQ<20>"
$PN"25"76;
"DQ<21>"
$PN"170"77;
"DQ<22>"
$PN"32"79;
"DQ<23>"
$PN"177"80;
"DQ<24>"
$PN"38"81;
"DQ<25>"
$PN"183"82;
"DQ<30>"
$PN"43"84;
"DQ<31>"
$PN"188"85;
"DQ<32>"
$PN"97"90;
"DQ<33>"
$PN"242"91;
"DQ<34>"
$PN"104"92;
"DQ<37>"
$PN"240"94;
"DQ<39>"
$PN"247"95;
"DQ<40>"
$PN"108"96;
"DQ<41>"
$PN"253"97;
"DQ<42>"
$PN"115"120;
"DQ<43>"
$PN"260"121;
"DQ<44>"
$PN"106"122;
"DQ<45>"
$PN"251"123;
"DQ<46>"
$PN"113"124;
"DQ<55>"
$PN"269"133;
"DQ<56>"
$PN"130"134;
"DQ<59>"
$PN"282"138;
"DQ<60>"
$PN"128"139;
"CKE<1>"
$PN"203"35;
"CK0N"
$PN"75"36;
"CB<0>"
$PN"49"37;
"CB<1>"
$PN"194"38;
"CB<2>"
$PN"56"39;
"CB<3>"
$PN"201"40;
"CB<4>"
$PN"47"41;
"CB<5>"
$PN"192"42;
"CB<6>"
$PN"54"43;
"A9"
$PN"66"105;
"A8"
$PN"68"106;
"A7"
$PN"211"107;
"A6"
$PN"69"108;
"A5"
$PN"213"109;
"A4"
$PN"214"117;
"A3"
$PN"71"110;
"A17"
$PN"234"111;
"A13"
$PN"232"112;
"A12"
$PN"65"113;
"A1"
$PN"72"114;
"A0"
$PN"79"115;
"C<2>"
$PN"235"30;
"DQ<28>"
$PN"36"86;
"DQ<29>"
$PN"181"87;
"S1_N"
$PN"89"44;
"S2_N_C<0>"
$PN"93"45;
"S3_N_C<1>"
$PN"237"46;
"CK0P"
$PN"74"51;
"CK1N"
$PN"219"50;
"BA<1>"
$PN"224"116;
%"TAP"
"6","(-3250,5150)","0","mstr_standard","I112";
;
HDL_TAP"TRUE"
BODY_TYPE"PLUMBING"
CDS_LIB"mstr_standard";
"B \NAC \NWC"4;
"S \NAC"
BN"17"111;
%"TAP"
"6","(-3250,5100)","0","mstr_standard","I113";
;
HDL_TAP"TRUE"
BODY_TYPE"PLUMBING"
CDS_LIB"mstr_standard";
"B \NAC \NWC"4;
"S \NAC"
BN"16"98;
%"TAP"
"6","(-3250,5050)","0","mstr_standard","I114";
;
HDL_TAP"TRUE"
BODY_TYPE"PLUMBING"
CDS_LIB"mstr_standard";
"B \NAC \NWC"4;
"S \NAC"
BN"15"99;
%"TAP"
"6","(-3250,5000)","0","mstr_standard","I115";
;
HDL_TAP"TRUE"
BODY_TYPE"PLUMBING"
CDS_LIB"mstr_standard";
"B \NAC \NWC"4;
"S \NAC"
BN"14"100;
%"TAP"
"6","(-3250,4950)","0","mstr_standard","I116";
;
HDL_TAP"TRUE"
BODY_TYPE"PLUMBING"
CDS_LIB"mstr_standard";
"B \NAC \NWC"4;
"S \NAC"
BN"13"112;
%"TAP"
"6","(-3250,4900)","0","mstr_standard","I117";
;
HDL_TAP"TRUE"
BODY_TYPE"PLUMBING"
CDS_LIB"mstr_standard";
"B \NAC \NWC"4;
"S \NAC"
BN"12"113;
%"TAP"
"6","(-3250,4850)","0","mstr_standard","I118";
;
HDL_TAP"TRUE"
BODY_TYPE"PLUMBING"
CDS_LIB"mstr_standard";
"B \NAC \NWC"4;
"S \NAC"
BN"11"101;
%"TAP"
"6","(-3250,4800)","0","mstr_standard","I119";
;
HDL_TAP"TRUE"
BODY_TYPE"PLUMBING"
CDS_LIB"mstr_standard";
"B \NAC \NWC"4;
"S \NAC"
BN"10"102;
%"TAP"
"6","(650,4900)","2","mstr_standard","I12";
;
HDL_TAP"TRUE"
BODY_TYPE"PLUMBING"
CDS_LIB"mstr_standard";
"B \NAC \NWC"1;
"S \NAC"
BN"14"165;
%"TAP"
"6","(-3250,4750)","0","mstr_standard","I120";
;
HDL_TAP"TRUE"
BODY_TYPE"PLUMBING"
CDS_LIB"mstr_standard";
"B \NAC \NWC"4;
"S \NAC"
BN"9"105;
%"TAP"
"6","(-3250,4700)","0","mstr_standard","I121";
;
HDL_TAP"TRUE"
BODY_TYPE"PLUMBING"
CDS_LIB"mstr_standard";
"B \NAC \NWC"4;
"S \NAC"
BN"8"106;
%"TAP"
"6","(-3250,4650)","0","mstr_standard","I122";
;
HDL_TAP"TRUE"
BODY_TYPE"PLUMBING"
CDS_LIB"mstr_standard";
"B \NAC \NWC"4;
"S \NAC"
BN"7"107;
%"TAP"
"6","(-3250,4600)","0","mstr_standard","I123";
;
HDL_TAP"TRUE"
BODY_TYPE"PLUMBING"
CDS_LIB"mstr_standard";
"B \NAC \NWC"4;
"S \NAC"
BN"6"108;
%"TAP"
"6","(-3250,4550)","0","mstr_standard","I124";
;
HDL_TAP"TRUE"
BODY_TYPE"PLUMBING"
CDS_LIB"mstr_standard";
"B \NAC \NWC"4;
"S \NAC"
BN"5"109;
%"TAP"
"6","(-3250,4500)","0","mstr_standard","I125";
;
HDL_TAP"TRUE"
BODY_TYPE"PLUMBING"
CDS_LIB"mstr_standard";
"B \NAC \NWC"4;
"S \NAC"
BN"4"117;
%"TAP"
"6","(-3250,4450)","0","mstr_standard","I126";
;
HDL_TAP"TRUE"
BODY_TYPE"PLUMBING"
CDS_LIB"mstr_standard";
"B \NAC \NWC"4;
"S \NAC"
BN"3"110;
%"TAP"
"6","(-3250,4400)","0","mstr_standard","I127";
;
HDL_TAP"TRUE"
BODY_TYPE"PLUMBING"
CDS_LIB"mstr_standard";
"B \NAC \NWC"4;
"S \NAC"
BN"2"103;
%"TAP"
"6","(-3250,4350)","0","mstr_standard","I128";
;
HDL_TAP"TRUE"
BODY_TYPE"PLUMBING"
CDS_LIB"mstr_standard";
"B \NAC \NWC"4;
"S \NAC"
BN"1"114;
%"TAP"
"6","(-3250,4300)","0","mstr_standard","I129";
;
HDL_TAP"TRUE"
BODY_TYPE"PLUMBING"
CDS_LIB"mstr_standard";
"B \NAC \NWC"4;
"S \NAC"
BN"0"115;
%"TAP"
"6","(650,4800)","2","mstr_standard","I13";
;
HDL_TAP"TRUE"
BODY_TYPE"PLUMBING"
CDS_LIB"mstr_standard";
"B \NAC \NWC"1;
"S \NAC"
BN"13"167;
%"TAP"
"6","(-3250,4200)","0","mstr_standard","I130";
;
HDL_TAP"TRUE"
BODY_TYPE"PLUMBING"
CDS_LIB"mstr_standard";
"B \NAC \NWC"5;
"S \NAC"
BN"1"116;
%"TAP"
"6","(-3250,4150)","0","mstr_standard","I133";
;
HDL_TAP"TRUE"
BODY_TYPE"PLUMBING"
CDS_LIB"mstr_standard";
"B \NAC \NWC"5;
"S \NAC"
BN"0"104;
%"TAP"
"6","(-3250,4100)","0","mstr_standard","I134";
;
HDL_TAP"TRUE"
BODY_TYPE"PLUMBING"
CDS_LIB"mstr_standard";
"B \NAC \NWC"3;
"S \NAC"
BN"1"118;
%"TAP"
"6","(-3250,4050)","0","mstr_standard","I135";
;
HDL_TAP"TRUE"
BODY_TYPE"PLUMBING"
CDS_LIB"mstr_standard";
"B \NAC \NWC"3;
"S \NAC"
BN"0"48;
%"TAP"
"6","(-3250,3050)","0","mstr_standard","I138";
;
HDL_TAP"TRUE"
BODY_TYPE"PLUMBING"
CDS_LIB"mstr_standard";
"B \NAC \NWC"10;
"S \NAC"
BN"7"43;
%"TAP"
"6","(-3250,3100)","0","mstr_standard","I139";
;
HDL_TAP"TRUE"
BODY_TYPE"PLUMBING"
CDS_LIB"mstr_standard";
"B \NAC \NWC"10;
"S \NAC"
BN"6"34;
%"TAP"
"6","(650,4600)","2","mstr_standard","I14";
;
HDL_TAP"TRUE"
BODY_TYPE"PLUMBING"
CDS_LIB"mstr_standard";
"B \NAC \NWC"1;
"S \NAC"
BN"11"171;
%"TAP"
"6","(-3250,3000)","0","mstr_standard","I140";
;
HDL_TAP"TRUE"
BODY_TYPE"PLUMBING"
CDS_LIB"mstr_standard";
"B \NAC \NWC"10;
"S \NAC"
BN"4"42;
%"TAP"
"6","(-3250,2950)","0","mstr_standard","I141";
;
HDL_TAP"TRUE"
BODY_TYPE"PLUMBING"
CDS_LIB"mstr_standard";
"B \NAC \NWC"10;
"S \NAC"
BN"5"41;
%"TAP"
"6","(-3250,2900)","0","mstr_standard","I142";
;
HDL_TAP"TRUE"
BODY_TYPE"PLUMBING"
CDS_LIB"mstr_standard";
"B \NAC \NWC"10;
"S \NAC"
BN"2"40;
%"TAP"
"6","(-3250,2850)","0","mstr_standard","I143";
;
HDL_TAP"TRUE"
BODY_TYPE"PLUMBING"
CDS_LIB"mstr_standard";
"B \NAC \NWC"10;
"S \NAC"
BN"3"39;
%"TAP"
"6","(-3250,2800)","0","mstr_standard","I144";
;
HDL_TAP"TRUE"
BODY_TYPE"PLUMBING"
CDS_LIB"mstr_standard";
"B \NAC \NWC"10;
"S \NAC"
BN"0"38;
%"TAP"
"6","(-3250,2750)","0","mstr_standard","I145";
;
HDL_TAP"TRUE"
BODY_TYPE"PLUMBING"
CDS_LIB"mstr_standard";
"B \NAC \NWC"10;
"S \NAC"
BN"1"37;
%"TAP"
"6","(650,4700)","2","mstr_standard","I15";
;
HDL_TAP"TRUE"
BODY_TYPE"PLUMBING"
CDS_LIB"mstr_standard";
"B \NAC \NWC"1;
"S \NAC"
BN"12"169;
%"TAP"
"6","(-3250,3950)","0","mstr_standard","I152";
;
HDL_TAP"TRUE"
BODY_TYPE"PLUMBING"
CDS_LIB"mstr_standard";
"B \NAC \NWC"7;
"S \NAC"
BN"1"49;
%"TAP"
"6","(-3250,3850)","0","mstr_standard","I153";
;
HDL_TAP"TRUE"
BODY_TYPE"PLUMBING"
CDS_LIB"mstr_standard";
"B \NAC \NWC"7;
"S \NAC"
BN"0"51;
%"TAP"
"6","(-3450,3900)","0","mstr_standard","I154";
;
HDL_TAP"TRUE"
BODY_TYPE"PLUMBING"
CDS_LIB"mstr_standard";
"B \NAC \NWC"11;
"S \NAC"
BN"1"50;
%"TAP"
"6","(-3450,3800)","0","mstr_standard","I155";
;
HDL_TAP"TRUE"
BODY_TYPE"PLUMBING"
CDS_LIB"mstr_standard";
"B \NAC \NWC"11;
"S \NAC"
BN"0"36;
%"TAP"
"6","(-3250,3650)","0","mstr_standard","I158";
;
HDL_TAP"TRUE"
BODY_TYPE"PLUMBING"
CDS_LIB"mstr_standard";
"B \NAC \NWC"9;
"S \NAC"
BN"3"46;
%"TAP"
"6","(-3250,3600)","0","mstr_standard","I159";
;
HDL_TAP"TRUE"
BODY_TYPE"PLUMBING"
CDS_LIB"mstr_standard";
"B \NAC \NWC"9;
"S \NAC"
BN"2"45;
%"PVDDQ_DEF"
"1","(-1225,2475)","0","mstr_symbols","I16";
;
HDL_POWER"PVDDQ_DEF"
ROOM"DDR4_CH_B"
BODY_TYPE"PLUMBING"
CDS_LIB"mstr_symbols"
BOM_COST"MEM"
VOLTAGE"1.2V";
"G\NAC"13;
%"TAP"
"6","(-3250,3550)","0","mstr_standard","I160";
;
HDL_TAP"TRUE"
BODY_TYPE"PLUMBING"
CDS_LIB"mstr_standard";
"B \NAC \NWC"9;
"S \NAC"
BN"1"44;
%"TAP"
"6","(-3250,3500)","0","mstr_standard","I161";
;
HDL_TAP"TRUE"
BODY_TYPE"PLUMBING"
CDS_LIB"mstr_standard";
"B \NAC \NWC"9;
"S \NAC"
BN"0"31;
%"TAP"
"6","(-3250,3400)","0","mstr_standard","I162";
;
HDL_TAP"TRUE"
BODY_TYPE"PLUMBING"
CDS_LIB"mstr_standard";
"B \NAC \NWC"8;
"S \NAC"
BN"1"35;
%"TAP"
"6","(-3250,3350)","0","mstr_standard","I163";
;
HDL_TAP"TRUE"
BODY_TYPE"PLUMBING"
CDS_LIB"mstr_standard";
"B \NAC \NWC"8;
"S \NAC"
BN"0"47;
%"TAP"
"6","(-3250,3250)","0","mstr_standard","I167";
;
HDL_TAP"TRUE"
BODY_TYPE"PLUMBING"
CDS_LIB"mstr_standard";
"B \NAC \NWC"12;
"S \NAC"
BN"1"32;
%"TAP"
"6","(-3250,3200)","0","mstr_standard","I168";
;
HDL_TAP"TRUE"
BODY_TYPE"PLUMBING"
CDS_LIB"mstr_standard";
"B \NAC \NWC"12;
"S \NAC"
BN"0"33;
%"SCONN288_H44441004"
"4","(-50,1950)","0","mstr_sconn","I169";
;
CDS_SEC"4"
ROOM"DDR4_CH_D"
CDS_LOCATION"J4B1"
SEC"4"
SEC_TYPE"PIP"
CDS_LIB"mstr_sconn"
BOM_COST"MEM"
PACK_TYPE"PIP"
MATERIAL"SCONN"
PART_NUMBER"H44441-004"
LOCATION"J4B1";
"VPP<4>"
$PN"142"18;
"VTT<1>"
$PN"77"14;
"VPP<0>"
$PN"287"18;
"VPP<1>"
$PN"286"18;
"VPP<2>"
$PN"288"18;
"VPP<3>"
$PN"143"18;
"VDD<1>"
$PN"233"13;
"VDD<2>"
$PN"231"13;
"VDD<3>"
$PN"229"13;
"VDD<4>"
$PN"226"13;
"VDD<5>"
$PN"223"13;
"VDD<7>"
$PN"217"13;
"VDD<8>"
$PN"215"13;
"VDD<9>"
$PN"212"13;
"VDD<11>"
$PN"206"13;
"VDD<12>"
$PN"204"13;
"VDD<14>"
$PN"90"13;
"VDD<15>"
$PN"88"13;
"VDD<17>"
$PN"83"13;
"VDD<18>"
$PN"80"13;
"VDD<20>"
$PN"73"13;
"VDD<21>"
$PN"70"13;
"VDD<22>"
$PN"67"13;
"VDD<24>"
$PN"61"13;
"12V<0>"
$PN"145"20;
"12V<1>"
$PN"1"20;
"VTT<0>"
$PN"221"14;
"VDD<25>"
$PN"59"13;
"VDD<23>"
$PN"64"13;
"VDD<19>"
$PN"76"13;
"VDD<16>"
$PN"85"13;
"VDD<13>"
$PN"92"13;
"VDD<10>"
$PN"209"13;
"VDD<6>"
$PN"220"13;
"VDD<0>"
$PN"236"13;
%"PVTT_DEF"
"1","(-925,2650)","0","mstr_symbols","I170";
;
HDL_POWER"PVTT_DEF"
ROOM"DDR4_CH_B"
BODY_TYPE"PLUMBING"
CDS_LIB"mstr_symbols"
BOM_COST"MEM"
VOLTAGE"0.6V";
"G\NAC"14;
%"GND"
"1","(2500,1150)","2","mstr_symbols","I171";
;
HDL_POWER"GND"
ROOM"DDR4_CH_B"
BODY_TYPE"PLUMBING"
BOM_COST"MEM"
CDS_LIB"mstr_symbols"
SIZE"1B"
VOLTAGE"0";
"A\NAC"15;
%"GND"
"1","(-5100,2100)","2","mstr_symbols","I178";
;
HDL_POWER"GND"
ROOM"DDR4_CH_B"
BODY_TYPE"PLUMBING"
BOM_COST"MEM"
SIZE"1B"
CDS_LIB"mstr_symbols"
VOLTAGE"0";
"A\NAC"16;
%"CAP_A"
"1","(-4650,1800)","2","dev_discrete","I179";
;
ROOM"DDR4_CH_B"
$SEC"1"
CDS_SEC"1"
CDS_LIB"dev_discrete"
BOM_COST"MEM"
CDS_LOCATION"C4B12"
MATERIAL"X7R"
VOLTAGE"25V"
PACK_TYPE"0402V"
TOLERANCE"10%"
VALUE"0.01UF"
PART_NUMBER"A36096-045"
LOCATION"C4B12";
"B"
$PN"2"17;
"A"
$PN"1"22;
%"GND"
"1","(-4650,1550)","0","mstr_symbols","I180";
;
HDL_POWER"GND"
ROOM"DDR4_CH_B"
BODY_TYPE"PLUMBING"
BOM_COST"MEM"
CDS_LIB"mstr_symbols"
SIZE"1B"
VOLTAGE"0";
"A\NAC"17;
%"PVPP_DEF"
"1","(-750,2950)","0","mstr_symbols","I181";
;
HDL_POWER"PVPP_DEF"
ROOM"DDR4_CH_B"
BODY_TYPE"PLUMBING"
CDS_LIB"mstr_symbols"
BOM_COST"MEM"
VOLTAGE"2.5V";
"G\NAC"18;
%"PVPP_DEF"
"1","(-5100,2500)","0","mstr_symbols","I182";
;
HDL_POWER"PVPP_DEF"
ROOM"DDR4_CH_B"
BODY_TYPE"PLUMBING"
CDS_LIB"mstr_symbols"
BOM_COST"MEM"
VOLTAGE"2.5V";
"G\NAC"19;
%"P12V_NVDIMM_DEF"
"1","(650,3025)","0","mstr_symbols","I184";
;
HDL_POWER"P12V_NVDIMM_DEF"
BODY_TYPE"PLUMBING"
CDS_LIB"mstr_symbols"
VOLTAGE"12.0";
"G\NAC"20;
%"TAP"
"6","(900,4550)","2","mstr_standard","I19";
;
HDL_TAP"TRUE"
BODY_TYPE"PLUMBING"
CDS_LIB"mstr_standard";
"B \NAC \NWC"2;
"S \NAC"
BN"11"172;
%"TAP"
"6","(900,4450)","2","mstr_standard","I20";
;
HDL_TAP"TRUE"
BODY_TYPE"PLUMBING"
CDS_LIB"mstr_standard";
"B \NAC \NWC"2;
"S \NAC"
BN"10"174;
%"TAP"
"6","(900,4350)","2","mstr_standard","I21";
;
HDL_TAP"TRUE"
BODY_TYPE"PLUMBING"
CDS_LIB"mstr_standard";
"B \NAC \NWC"2;
"S \NAC"
BN"9"155;
%"TAP"
"6","(900,4250)","2","mstr_standard","I22";
;
HDL_TAP"TRUE"
BODY_TYPE"PLUMBING"
CDS_LIB"mstr_standard";
"B \NAC \NWC"2;
"S \NAC"
BN"8"157;
%"TAP"
"6","(900,4150)","2","mstr_standard","I23";
;
HDL_TAP"TRUE"
BODY_TYPE"PLUMBING"
CDS_LIB"mstr_standard";
"B \NAC \NWC"2;
"S \NAC"
BN"7"159;
%"TAP"
"6","(650,4400)","2","mstr_standard","I24";
;
HDL_TAP"TRUE"
BODY_TYPE"PLUMBING"
CDS_LIB"mstr_standard";
"B \NAC \NWC"1;
"S \NAC"
BN"9"154;
%"TAP"
"6","(650,4500)","2","mstr_standard","I25";
;
HDL_TAP"TRUE"
BODY_TYPE"PLUMBING"
CDS_LIB"mstr_standard";
"B \NAC \NWC"1;
"S \NAC"
BN"10"173;
%"TAP"
"6","(650,4300)","2","mstr_standard","I26";
;
HDL_TAP"TRUE"
BODY_TYPE"PLUMBING"
CDS_LIB"mstr_standard";
"B \NAC \NWC"1;
"S \NAC"
BN"8"156;
%"TAP"
"6","(650,4100)","2","mstr_standard","I27";
;
HDL_TAP"TRUE"
BODY_TYPE"PLUMBING"
CDS_LIB"mstr_standard";
"B \NAC \NWC"1;
"S \NAC"
BN"6"160;
%"TAP"
"6","(650,4200)","2","mstr_standard","I28";
;
HDL_TAP"TRUE"
BODY_TYPE"PLUMBING"
CDS_LIB"mstr_standard";
"B \NAC \NWC"1;
"S \NAC"
BN"7"158;
%"TAP"
"6","(900,4050)","2","mstr_standard","I29";
;
HDL_TAP"TRUE"
BODY_TYPE"PLUMBING"
CDS_LIB"mstr_standard";
"B \NAC \NWC"2;
"S \NAC"
BN"6"141;
%"TAP"
"6","(900,5150)","2","mstr_standard","I3";
;
HDL_TAP"TRUE"
BODY_TYPE"PLUMBING"
CDS_LIB"mstr_standard";
"B \NAC \NWC"2;
"S \NAC"
BN"17"176;
%"TAP"
"6","(900,3950)","2","mstr_standard","I30";
;
HDL_TAP"TRUE"
BODY_TYPE"PLUMBING"
CDS_LIB"mstr_standard";
"B \NAC \NWC"2;
"S \NAC"
BN"5"143;
%"TAP"
"6","(900,3850)","2","mstr_standard","I31";
;
HDL_TAP"TRUE"
BODY_TYPE"PLUMBING"
CDS_LIB"mstr_standard";
"B \NAC \NWC"2;
"S \NAC"
BN"4"145;
%"TAP"
"6","(900,3750)","2","mstr_standard","I32";
;
HDL_TAP"TRUE"
BODY_TYPE"PLUMBING"
CDS_LIB"mstr_standard";
"B \NAC \NWC"2;
"S \NAC"
BN"3"147;
%"TAP"
"6","(900,3650)","2","mstr_standard","I33";
;
HDL_TAP"TRUE"
BODY_TYPE"PLUMBING"
CDS_LIB"mstr_standard";
"B \NAC \NWC"2;
"S \NAC"
BN"2"149;
%"TAP"
"6","(650,3900)","2","mstr_standard","I34";
;
HDL_TAP"TRUE"
BODY_TYPE"PLUMBING"
CDS_LIB"mstr_standard";
"B \NAC \NWC"1;
"S \NAC"
BN"4"144;
%"TAP"
"6","(650,4000)","2","mstr_standard","I35";
;
HDL_TAP"TRUE"
BODY_TYPE"PLUMBING"
CDS_LIB"mstr_standard";
"B \NAC \NWC"1;
"S \NAC"
BN"5"142;
%"TAP"
"6","(650,3800)","2","mstr_standard","I36";
;
HDL_TAP"TRUE"
BODY_TYPE"PLUMBING"
CDS_LIB"mstr_standard";
"B \NAC \NWC"1;
"S \NAC"
BN"3"146;
%"TAP"
"6","(650,3700)","2","mstr_standard","I37";
;
HDL_TAP"TRUE"
BODY_TYPE"PLUMBING"
CDS_LIB"mstr_standard";
"B \NAC \NWC"1;
"S \NAC"
BN"2"148;
%"TAP"
"6","(650,3600)","2","mstr_standard","I38";
;
HDL_TAP"TRUE"
BODY_TYPE"PLUMBING"
CDS_LIB"mstr_standard";
"B \NAC \NWC"1;
"S \NAC"
BN"1"150;
%"TAP"
"6","(900,3450)","2","mstr_standard","I39";
;
HDL_TAP"TRUE"
BODY_TYPE"PLUMBING"
CDS_LIB"mstr_standard";
"B \NAC \NWC"2;
"S \NAC"
BN"0"153;
%"TAP"
"6","(650,5200)","2","mstr_standard","I4";
;
HDL_TAP"TRUE"
BODY_TYPE"PLUMBING"
CDS_LIB"mstr_standard";
"B \NAC \NWC"1;
"S \NAC"
BN"17"175;
%"TAP"
"6","(900,3550)","2","mstr_standard","I40";
;
HDL_TAP"TRUE"
BODY_TYPE"PLUMBING"
CDS_LIB"mstr_standard";
"B \NAC \NWC"2;
"S \NAC"
BN"1"151;
%"TAP"
"6","(650,3500)","2","mstr_standard","I41";
;
HDL_TAP"TRUE"
BODY_TYPE"PLUMBING"
CDS_LIB"mstr_standard";
"B \NAC \NWC"1;
"S \NAC"
BN"0"152;
%"SCONN288_H44441004"
"3","(1800,2450)","0","mstr_sconn","I43";
;
CDS_SEC"3"
ROOM"DDR4_CH_D"
CDS_LOCATION"J4B1"
SEC"3"
SEC_TYPE"PIP"
CDS_LIB"mstr_sconn"
BOM_COST"MEM"
PACK_TYPE"PIP"
MATERIAL"SCONN"
PART_NUMBER"H44441-004"
LOCATION"J4B1";
"VSS<93>"
$PN"2"21;
"VSS<92>"
$PN"4"21;
"VSS<91>"
$PN"6"21;
"VSS<90>"
$PN"9"21;
"VSS<89>"
$PN"11"21;
"VSS<88>"
$PN"13"21;
"VSS<0>"
$PN"283"15;
"VSS<1>"
$PN"281"15;
"VSS<2>"
$PN"279"15;
"VSS<3>"
$PN"276"15;
"VSS<4>"
$PN"274"15;
"VSS<5>"
$PN"272"15;
"VSS<6>"
$PN"270"15;
"VSS<7>"
$PN"268"15;
"VSS<8>"
$PN"265"15;
"VSS<9>"
$PN"263"15;
"VSS<10>"
$PN"261"15;
"VSS<11>"
$PN"259"15;
"VSS<12>"
$PN"257"15;
"VSS<13>"
$PN"254"15;
"VSS<14>"
$PN"252"15;
"VSS<15>"
$PN"250"15;
"VSS<16>"
$PN"248"15;
"VSS<17>"
$PN"246"15;
"VSS<18>"
$PN"243"15;
"VSS<19>"
$PN"241"15;
"VSS<20>"
$PN"239"15;
"VSS<21>"
$PN"202"15;
"VSS<22>"
$PN"200"15;
"VSS<23>"
$PN"198"15;
"VSS<24>"
$PN"195"15;
"VSS<25>"
$PN"193"15;
"VSS<26>"
$PN"191"15;
"VSS<27>"
$PN"189"15;
"VSS<28>"
$PN"187"15;
"VSS<29>"
$PN"184"15;
"VSS<30>"
$PN"182"15;
"VSS<31>"
$PN"180"15;
"VSS<32>"
$PN"178"15;
"VSS<33>"
$PN"176"15;
"VSS<34>"
$PN"173"15;
"VSS<35>"
$PN"171"15;
"VSS<36>"
$PN"169"15;
"VSS<37>"
$PN"167"15;
"VSS<38>"
$PN"165"15;
"VSS<39>"
$PN"162"15;
"VSS<40>"
$PN"160"15;
"VSS<41>"
$PN"158"15;
"VSS<42>"
$PN"156"15;
"VSS<43>"
$PN"154"15;
"VSS<44>"
$PN"151"15;
"VSS<47>"
$PN"138"21;
"VSS<48>"
$PN"136"21;
"VSS<49>"
$PN"134"21;
"VSS<50>"
$PN"131"21;
"VSS<51>"
$PN"129"21;
"VSS<52>"
$PN"127"21;
"VSS<53>"
$PN"125"21;
"VSS<54>"
$PN"123"21;
"VSS<55>"
$PN"120"21;
"VSS<56>"
$PN"118"21;
"VSS<57>"
$PN"116"21;
"VSS<58>"
$PN"114"21;
"VSS<59>"
$PN"112"21;
"VSS<60>"
$PN"109"21;
"VSS<61>"
$PN"107"21;
"VSS<62>"
$PN"105"21;
"VSS<63>"
$PN"103"21;
"VSS<64>"
$PN"101"21;
"VSS<65>"
$PN"98"21;
"VSS<66>"
$PN"96"21;
"VSS<67>"
$PN"94"21;
"VSS<68>"
$PN"57"21;
"VSS<69>"
$PN"55"21;
"VSS<70>"
$PN"53"21;
"VSS<71>"
$PN"50"21;
"VSS<72>"
$PN"48"21;
"VSS<73>"
$PN"46"21;
"VSS<74>"
$PN"44"21;
"VSS<75>"
$PN"42"21;
"VSS<76>"
$PN"39"21;
"VSS<77>"
$PN"37"21;
"VSS<78>"
$PN"35"21;
"VSS<79>"
$PN"33"21;
"VSS<80>"
$PN"31"21;
"VSS<81>"
$PN"28"21;
"VSS<82>"
$PN"26"21;
"VSS<83>"
$PN"24"21;
"VSS<84>"
$PN"22"21;
"VSS<85>"
$PN"20"21;
"VSS<86>"
$PN"17"21;
"VSS<87>"
$PN"15"21;
"VSS<45>"
$PN"149"15;
"VSS<46>"
$PN"147"15;
%"GND"
"1","(1100,1150)","2","mstr_symbols","I44";
;
HDL_POWER"GND"
ROOM"DDR4_CH_B"
BODY_TYPE"PLUMBING"
BOM_COST"MEM"
CDS_LIB"mstr_symbols"
SIZE"1B"
VOLTAGE"0";
"A\NAC"21;
%"TAP"
"6","(-1750,5150)","2","mstr_standard","I46";
;
HDL_TAP"TRUE"
BODY_TYPE"PLUMBING"
CDS_LIB"mstr_standard";
"B \NAC \NWC"6;
"S \NAC"
BN"62"140;
%"TAP"
"6","(-1750,5100)","2","mstr_standard","I47";
;
HDL_TAP"TRUE"
BODY_TYPE"PLUMBING"
CDS_LIB"mstr_standard";
"B \NAC \NWC"6;
"S \NAC"
BN"63"135;
%"TAP"
"6","(-1750,5000)","2","mstr_standard","I48";
;
HDL_TAP"TRUE"
BODY_TYPE"PLUMBING"
CDS_LIB"mstr_standard";
"B \NAC \NWC"6;
"S \NAC"
BN"61"139;
%"TAP"
"6","(-1750,5050)","2","mstr_standard","I49";
;
HDL_TAP"TRUE"
BODY_TYPE"PLUMBING"
CDS_LIB"mstr_standard";
"B \NAC \NWC"6;
"S \NAC"
BN"60"136;
%"TAP"
"6","(900,5050)","2","mstr_standard","I5";
;
HDL_TAP"TRUE"
BODY_TYPE"PLUMBING"
CDS_LIB"mstr_standard";
"B \NAC \NWC"2;
"S \NAC"
BN"16"162;
%"TAP"
"6","(-1750,4950)","2","mstr_standard","I50";
;
HDL_TAP"TRUE"
BODY_TYPE"PLUMBING"
CDS_LIB"mstr_standard";
"B \NAC \NWC"6;
"S \NAC"
BN"58"138;
%"TAP"
"6","(-1750,4850)","2","mstr_standard","I51";
;
HDL_TAP"TRUE"
BODY_TYPE"PLUMBING"
CDS_LIB"mstr_standard";
"B \NAC \NWC"6;
"S \NAC"
BN"56"132;
%"TAP"
"6","(-1750,4900)","2","mstr_standard","I52";
;
HDL_TAP"TRUE"
BODY_TYPE"PLUMBING"
CDS_LIB"mstr_standard";
"B \NAC \NWC"6;
"S \NAC"
BN"59"137;
%"TAP"
"6","(-1750,4800)","2","mstr_standard","I53";
;
HDL_TAP"TRUE"
BODY_TYPE"PLUMBING"
CDS_LIB"mstr_standard";
"B \NAC \NWC"6;
"S \NAC"
BN"57"134;
%"TAP"
"6","(-1750,4750)","2","mstr_standard","I54";
;
HDL_TAP"TRUE"
BODY_TYPE"PLUMBING"
CDS_LIB"mstr_standard";
"B \NAC \NWC"6;
"S \NAC"
BN"54"133;
%"TAP"
"6","(-1750,4650)","2","mstr_standard","I55";
;
HDL_TAP"TRUE"
BODY_TYPE"PLUMBING"
CDS_LIB"mstr_standard";
"B \NAC \NWC"6;
"S \NAC"
BN"52"130;
%"TAP"
"6","(-1750,4700)","2","mstr_standard","I56";
;
HDL_TAP"TRUE"
BODY_TYPE"PLUMBING"
CDS_LIB"mstr_standard";
"B \NAC \NWC"6;
"S \NAC"
BN"55"131;
%"TAP"
"6","(-1750,4600)","2","mstr_standard","I57";
;
HDL_TAP"TRUE"
BODY_TYPE"PLUMBING"
CDS_LIB"mstr_standard";
"B \NAC \NWC"6;
"S \NAC"
BN"53"129;
%"TAP"
"6","(-1750,4550)","2","mstr_standard","I58";
;
HDL_TAP"TRUE"
BODY_TYPE"PLUMBING"
CDS_LIB"mstr_standard";
"B \NAC \NWC"6;
"S \NAC"
BN"50"128;
%"TAP"
"6","(-1750,4500)","2","mstr_standard","I59";
;
HDL_TAP"TRUE"
BODY_TYPE"PLUMBING"
CDS_LIB"mstr_standard";
"B \NAC \NWC"6;
"S \NAC"
BN"51"127;
%"TAP"
"6","(900,4950)","2","mstr_standard","I6";
;
HDL_TAP"TRUE"
BODY_TYPE"PLUMBING"
CDS_LIB"mstr_standard";
"B \NAC \NWC"2;
"S \NAC"
BN"15"164;
%"TAP"
"6","(-1750,4450)","2","mstr_standard","I60";
;
HDL_TAP"TRUE"
BODY_TYPE"PLUMBING"
CDS_LIB"mstr_standard";
"B \NAC \NWC"6;
"S \NAC"
BN"48"126;
%"TAP"
"6","(-1750,4350)","2","mstr_standard","I61";
;
HDL_TAP"TRUE"
BODY_TYPE"PLUMBING"
CDS_LIB"mstr_standard";
"B \NAC \NWC"6;
"S \NAC"
BN"46"119;
%"TAP"
"6","(-1750,4400)","2","mstr_standard","I62";
;
HDL_TAP"TRUE"
BODY_TYPE"PLUMBING"
CDS_LIB"mstr_standard";
"B \NAC \NWC"6;
"S \NAC"
BN"49"125;
%"TAP"
"6","(-1750,4300)","2","mstr_standard","I63";
;
HDL_TAP"TRUE"
BODY_TYPE"PLUMBING"
CDS_LIB"mstr_standard";
"B \NAC \NWC"6;
"S \NAC"
BN"47"124;
%"TAP"
"6","(-1750,4250)","2","mstr_standard","I64";
;
HDL_TAP"TRUE"
BODY_TYPE"PLUMBING"
CDS_LIB"mstr_standard";
"B \NAC \NWC"6;
"S \NAC"
BN"44"123;
%"TAP"
"6","(-1750,4200)","2","mstr_standard","I65";
;
HDL_TAP"TRUE"
BODY_TYPE"PLUMBING"
CDS_LIB"mstr_standard";
"B \NAC \NWC"6;
"S \NAC"
BN"45"122;
%"SCONN288_H44441004"
"2","(-50,4350)","0","mstr_sconn","I66";
;
CDS_SEC"2"
ROOM"DDR4_CH_D"
CDS_LOCATION"J4B1"
SEC"2"
SEC_TYPE"PIP"
CDS_LIB"mstr_sconn"
BOM_COST"MEM"
PACK_TYPE"PIP"
MATERIAL"SCONN"
PART_NUMBER"H44441-004"
LOCATION"J4B1";
"DQS17P"
$PN"51"175;
"DQS9P"
$PN"7"154;
"DQS9N"
$PN"8"155;
"DQS8P"
$PN"197"156;
"DQS8N"
$PN"196"157;
"DQS7P"
$PN"278"158;
"DQS7N"
$PN"277"159;
"DQS6P"
$PN"267"160;
"DQS6N"
$PN"266"141;
"DQS5P"
$PN"256"142;
"DQS5N"
$PN"255"143;
"DQS4P"
$PN"245"144;
"DQS4N"
$PN"244"145;
"DQS3P"
$PN"186"146;
"DQS3N"
$PN"185"147;
"DQS2P"
$PN"175"148;
"DQS2N"
$PN"174"149;
"DQS1P"
$PN"164"150;
"DQS1N"
$PN"163"151;
"DQS17N"
$PN"52"176;
"DQS16P"
$PN"132"161;
"DQS16N"
$PN"133"162;
"DQS15P"
$PN"121"163;
"DQS15N"
$PN"122"164;
"DQS14P"
$PN"110"165;
"DQS14N"
$PN"111"166;
"DQS13P"
$PN"99"167;
"DQS13N"
$PN"100"168;
"DQS12P"
$PN"40"169;
"DQS12N"
$PN"41"170;
"DQS11P"
$PN"29"171;
"DQS11N"
$PN"30"172;
"DQS10P"
$PN"18"173;
"DQS10N"
$PN"19"174;
"DQS0P"
$PN"153"152;
"DQS0N"
$PN"152"153;
%"TAP"
"6","(-1750,4150)","2","mstr_standard","I67";
;
HDL_TAP"TRUE"
BODY_TYPE"PLUMBING"
CDS_LIB"mstr_standard";
"B \NAC \NWC"6;
"S \NAC"
BN"42"121;
%"TAP"
"6","(-1750,4100)","2","mstr_standard","I68";
;
HDL_TAP"TRUE"
BODY_TYPE"PLUMBING"
CDS_LIB"mstr_standard";
"B \NAC \NWC"6;
"S \NAC"
BN"43"120;
%"TAP"
"6","(-1750,4000)","2","mstr_standard","I69";
;
HDL_TAP"TRUE"
BODY_TYPE"PLUMBING"
CDS_LIB"mstr_standard";
"B \NAC \NWC"6;
"S \NAC"
BN"41"96;
%"TAP"
"6","(900,4750)","2","mstr_standard","I7";
;
HDL_TAP"TRUE"
BODY_TYPE"PLUMBING"
CDS_LIB"mstr_standard";
"B \NAC \NWC"2;
"S \NAC"
BN"13"168;
%"TAP"
"6","(-1750,3950)","2","mstr_standard","I70";
;
HDL_TAP"TRUE"
BODY_TYPE"PLUMBING"
CDS_LIB"mstr_standard";
"B \NAC \NWC"6;
"S \NAC"
BN"38"95;
%"TAP"
"6","(-1750,4050)","2","mstr_standard","I71";
;
HDL_TAP"TRUE"
BODY_TYPE"PLUMBING"
CDS_LIB"mstr_standard";
"B \NAC \NWC"6;
"S \NAC"
BN"40"97;
%"TAP"
"6","(-1750,3900)","2","mstr_standard","I72";
;
HDL_TAP"TRUE"
BODY_TYPE"PLUMBING"
CDS_LIB"mstr_standard";
"B \NAC \NWC"6;
"S \NAC"
BN"39"93;
%"TAP"
"6","(-1750,3850)","2","mstr_standard","I73";
;
HDL_TAP"TRUE"
BODY_TYPE"PLUMBING"
CDS_LIB"mstr_standard";
"B \NAC \NWC"6;
"S \NAC"
BN"36"94;
%"TAP"
"6","(-1750,3800)","2","mstr_standard","I74";
;
HDL_TAP"TRUE"
BODY_TYPE"PLUMBING"
CDS_LIB"mstr_standard";
"B \NAC \NWC"6;
"S \NAC"
BN"37"88;
%"TAP"
"6","(-1750,3700)","2","mstr_standard","I75";
;
HDL_TAP"TRUE"
BODY_TYPE"PLUMBING"
CDS_LIB"mstr_standard";
"B \NAC \NWC"6;
"S \NAC"
BN"35"92;
%"TAP"
"6","(-1750,3750)","2","mstr_standard","I76";
;
HDL_TAP"TRUE"
BODY_TYPE"PLUMBING"
CDS_LIB"mstr_standard";
"B \NAC \NWC"6;
"S \NAC"
BN"34"89;
%"TAP"
"6","(-1750,3650)","2","mstr_standard","I77";
;
HDL_TAP"TRUE"
BODY_TYPE"PLUMBING"
CDS_LIB"mstr_standard";
"B \NAC \NWC"6;
"S \NAC"
BN"32"91;
%"TAP"
"6","(-1750,3600)","2","mstr_standard","I78";
;
HDL_TAP"TRUE"
BODY_TYPE"PLUMBING"
CDS_LIB"mstr_standard";
"B \NAC \NWC"6;
"S \NAC"
BN"33"90;
%"TAP"
"6","(-1750,3450)","2","mstr_standard","I79";
;
HDL_TAP"TRUE"
BODY_TYPE"PLUMBING"
CDS_LIB"mstr_standard";
"B \NAC \NWC"6;
"S \NAC"
BN"28"87;
%"TAP"
"6","(900,4850)","2","mstr_standard","I8";
;
HDL_TAP"TRUE"
BODY_TYPE"PLUMBING"
CDS_LIB"mstr_standard";
"B \NAC \NWC"2;
"S \NAC"
BN"14"166;
%"TAP"
"6","(-1750,3550)","2","mstr_standard","I80";
;
HDL_TAP"TRUE"
BODY_TYPE"PLUMBING"
CDS_LIB"mstr_standard";
"B \NAC \NWC"6;
"S \NAC"
BN"30"85;
%"TAP"
"6","(-1750,3500)","2","mstr_standard","I81";
;
HDL_TAP"TRUE"
BODY_TYPE"PLUMBING"
CDS_LIB"mstr_standard";
"B \NAC \NWC"6;
"S \NAC"
BN"31"84;
%"TAP"
"6","(-1750,3350)","2","mstr_standard","I82";
;
HDL_TAP"TRUE"
BODY_TYPE"PLUMBING"
CDS_LIB"mstr_standard";
"B \NAC \NWC"6;
"S \NAC"
BN"26"83;
%"TAP"
"6","(-1750,3400)","2","mstr_standard","I83";
;
HDL_TAP"TRUE"
BODY_TYPE"PLUMBING"
CDS_LIB"mstr_standard";
"B \NAC \NWC"6;
"S \NAC"
BN"29"86;
%"TAP"
"6","(-1750,3300)","2","mstr_standard","I84";
;
HDL_TAP"TRUE"
BODY_TYPE"PLUMBING"
CDS_LIB"mstr_standard";
"B \NAC \NWC"6;
"S \NAC"
BN"27"78;
%"TAP"
"6","(-1750,3200)","2","mstr_standard","I85";
;
HDL_TAP"TRUE"
BODY_TYPE"PLUMBING"
CDS_LIB"mstr_standard";
"B \NAC \NWC"6;
"S \NAC"
BN"25"81;
%"TAP"
"6","(-1750,3250)","2","mstr_standard","I86";
;
HDL_TAP"TRUE"
BODY_TYPE"PLUMBING"
CDS_LIB"mstr_standard";
"B \NAC \NWC"6;
"S \NAC"
BN"24"82;
%"TAP"
"6","(-1750,3100)","2","mstr_standard","I87";
;
HDL_TAP"TRUE"
BODY_TYPE"PLUMBING"
CDS_LIB"mstr_standard";
"B \NAC \NWC"6;
"S \NAC"
BN"23"79;
%"TAP"
"6","(-1750,3150)","2","mstr_standard","I88";
;
HDL_TAP"TRUE"
BODY_TYPE"PLUMBING"
CDS_LIB"mstr_standard";
"B \NAC \NWC"6;
"S \NAC"
BN"22"80;
%"TAP"
"6","(-1750,3050)","2","mstr_standard","I89";
;
HDL_TAP"TRUE"
BODY_TYPE"PLUMBING"
CDS_LIB"mstr_standard";
"B \NAC \NWC"6;
"S \NAC"
BN"20"77;
%"TAP"
"6","(900,4650)","2","mstr_standard","I9";
;
HDL_TAP"TRUE"
BODY_TYPE"PLUMBING"
CDS_LIB"mstr_standard";
"B \NAC \NWC"2;
"S \NAC"
BN"12"170;
%"TAP"
"6","(-1750,3000)","2","mstr_standard","I90";
;
HDL_TAP"TRUE"
BODY_TYPE"PLUMBING"
CDS_LIB"mstr_standard";
"B \NAC \NWC"6;
"S \NAC"
BN"21"76;
%"TAP"
"6","(-1750,2950)","2","mstr_standard","I91";
;
HDL_TAP"TRUE"
BODY_TYPE"PLUMBING"
CDS_LIB"mstr_standard";
"B \NAC \NWC"6;
"S \NAC"
BN"18"75;
%"TAP"
"6","(-1750,2900)","2","mstr_standard","I92";
;
HDL_TAP"TRUE"
BODY_TYPE"PLUMBING"
CDS_LIB"mstr_standard";
"B \NAC \NWC"6;
"S \NAC"
BN"19"74;
%"TAP"
"6","(-1750,2800)","2","mstr_standard","I93";
;
HDL_TAP"TRUE"
BODY_TYPE"PLUMBING"
CDS_LIB"mstr_standard";
"B \NAC \NWC"6;
"S \NAC"
BN"17"72;
%"TAP"
"6","(-1750,2850)","2","mstr_standard","I94";
;
HDL_TAP"TRUE"
BODY_TYPE"PLUMBING"
CDS_LIB"mstr_standard";
"B \NAC \NWC"6;
"S \NAC"
BN"16"73;
%"TAP"
"6","(-1750,2750)","2","mstr_standard","I95";
;
HDL_TAP"TRUE"
BODY_TYPE"PLUMBING"
CDS_LIB"mstr_standard";
"B \NAC \NWC"6;
"S \NAC"
BN"14"68;
%"TAP"
"6","(-1750,2700)","2","mstr_standard","I96";
;
HDL_TAP"TRUE"
BODY_TYPE"PLUMBING"
CDS_LIB"mstr_standard";
"B \NAC \NWC"6;
"S \NAC"
BN"15"71;
%"TAP"
"6","(-1750,2600)","2","mstr_standard","I97";
;
HDL_TAP"TRUE"
BODY_TYPE"PLUMBING"
CDS_LIB"mstr_standard";
"B \NAC \NWC"6;
"S \NAC"
BN"13"69;
%"TAP"
"6","(-1750,2650)","2","mstr_standard","I98";
;
HDL_TAP"TRUE"
BODY_TYPE"PLUMBING"
CDS_LIB"mstr_standard";
"B \NAC \NWC"6;
"S \NAC"
BN"12"70;
%"TAP"
"6","(-1750,2550)","2","mstr_standard","I99";
;
HDL_TAP"TRUE"
BODY_TYPE"PLUMBING"
CDS_LIB"mstr_standard";
"B \NAC \NWC"6;
"S \NAC"
BN"10"66;
END.
